FILE_TYPE = MACRO_DRAWING;
SET COLOR_WIRE YELLOW;
SET COLOR_PROP ORANGE;
SET COLOR_DOT WHITE;
SET COLOR_ARC YELLOW;
SET COLOR_BODY GREEN;
SET COLOR_NOTE PURPLE;
SET PROP_DISPLAY VALUE;
SET PAGE_NUMBER P37;
SET PATH_NUMBER P3;
FORCEADD LCMXO3LF2100C5BG256C..4
(-4825 4625);
FORCEPROP 1 LAST PART_NUMBER AJ021000T03
J 0
(-5314 5313);
DISPLAY 0.723404 (-5314 5313);
PAINT GREEN (-5314 5313);
FORCEPROP 2 LAST VALUE LCMXO3LF-2100C-5BG256C
J 0
(-5300 5450);
DISPLAY 0.680851 (-5300 5450);
FORCEPROP 1 LAST MATERIAL IC
J 0
(-5314 5234);
DISPLAY 0.723404 (-5314 5234);
PAINT GREEN (-5314 5234);
FORCEPROP 2 LAST PART_TYPE SMLF
J 0
(-5300 5500);
DISPLAY 0.680851 (-5300 5500);
FORCEPROP 1 LAST CDS_LMAN_SYM_OUTLINE -500,600,500,-600
J 0
(-4825 4625);
DISPLAY 0.468085 (-4825 4625);
PAINT GREEN (-4825 4625);
DISPLAY INVISIBLE (-4825 4625);
FORCEPROP 1 LAST NEEDS_NO_SIZE TRUE
J 0
(-4825 4625);
DISPLAY 0.723404 (-4825 4625);
PAINT GREEN (-4825 4625);
DISPLAY INVISIBLE (-4825 4625);
FORCEPROP 1 LAST PATH I1
J 0
(-4825 4625);
DISPLAY 0.723404 (-4825 4625);
PAINT GREEN (-4825 4625);
DISPLAY INVISIBLE (-4825 4625);
FORCEPROP 2 LAST CDS_LIB pure_quanta
J 0
(-4825 4625);
DISPLAY INVISIBLE (-4825 4625);
FORCEPROP 1 LAST LOCATION U25
J 0
(-5314 5412);
DISPLAY 0.723404 (-5314 5412);
PAINT GREEN (-5314 5412);
FORCEPROP 0 LASTPIN (-5475 5025) $PN L1
J 2
(-5485 5035);
DISPLAY 0.680851 (-5485 5035);
PAINT MONO (-5485 5035);
FORCEPROP 0 LASTPIN (-5475 4975) $PN L3
J 2
(-5485 4985);
DISPLAY 0.680851 (-5485 4985);
PAINT MONO (-5485 4985);
FORCEPROP 0 LASTPIN (-5475 4875) $PN K4
J 2
(-5485 4885);
DISPLAY 0.680851 (-5485 4885);
PAINT MONO (-5485 4885);
FORCEPROP 0 LASTPIN (-5475 4825) $PN L5
J 2
(-5485 4835);
DISPLAY 0.680851 (-5485 4835);
PAINT MONO (-5485 4835);
FORCEPROP 0 LASTPIN (-5475 4475) $PN L2
J 2
(-5485 4485);
DISPLAY 0.680851 (-5485 4485);
PAINT MONO (-5485 4485);
FORCEPROP 0 LASTPIN (-5475 4425) $PN M1
J 2
(-5485 4435);
DISPLAY 0.680851 (-5485 4435);
PAINT MONO (-5485 4435);
FORCEPROP 0 LASTPIN (-5475 4725) $PN K5
J 2
(-5485 4735);
DISPLAY 0.680851 (-5485 4735);
PAINT MONO (-5485 4735);
FORCEPROP 0 LASTPIN (-5475 4675) $PN L4
J 2
(-5485 4685);
DISPLAY 0.680851 (-5485 4685);
PAINT MONO (-5485 4685);
FORCEPROP 0 LASTPIN (-4175 4925) $PN M3
J 0
(-4165 4935);
DISPLAY 0.680851 (-4165 4935);
PAINT MONO (-4165 4935);
FORCEPROP 0 LASTPIN (-4175 4875) $PN N1
J 0
(-4165 4885);
DISPLAY 0.680851 (-4165 4885);
PAINT MONO (-4165 4885);
FORCEPROP 0 LASTPIN (-4175 5075) $PN N2
J 0
(-4165 5085);
DISPLAY 0.680851 (-4165 5085);
PAINT MONO (-4165 5085);
FORCEPROP 0 LASTPIN (-4175 5025) $PN P1
J 0
(-4165 5035);
DISPLAY 0.680851 (-4165 5035);
PAINT MONO (-4165 5035);
FORCEPROP 0 LASTPIN (-4175 4775) $PN M2
J 0
(-4165 4785);
DISPLAY 0.680851 (-4165 4785);
PAINT MONO (-4165 4785);
FORCEPROP 0 LASTPIN (-4175 4725) $PN N3
J 0
(-4165 4735);
DISPLAY 0.680851 (-4165 4735);
PAINT MONO (-4165 4735);
FORCEPROP 0 LASTPIN (-4175 4625) $PN R1
J 0
(-4165 4635);
DISPLAY 0.680851 (-4165 4635);
PAINT MONO (-4165 4635);
FORCEPROP 0 LASTPIN (-4175 4575) $PN P2
J 0
(-4165 4585);
DISPLAY 0.680851 (-4165 4585);
PAINT MONO (-4165 4585);
FORCEPROP 0 LASTPIN (-4175 4225) $PN M4
J 0
(-4165 4235);
DISPLAY 0.680851 (-4165 4235);
PAINT MONO (-4165 4235);
FORCEPROP 0 LAST $SEC 4
J 0
(-5300 5550);
DISPLAY 0.680851 (-5300 5550);
PAINT MONO (-5300 5550);
DISPLAY INVISIBLE (-5300 5550);
FORCEPROP 0 LAST CDS_SEC 4
J 0
(-5300 5550);
DISPLAY 0.680851 (-5300 5550);
DISPLAY INVISIBLE (-5300 5550);
FORCEADD UNIVERSAL_POWER..1
(-3800 4325);
FORCEPROP 3 LASTPIN (-3800 4275) SIG_NAME VCCIO3\g
J 0
(-3790 4285);
DISPLAY 0.659574 (-3790 4285);
PAINT MONO (-3790 4285);
DISPLAY INVISIBLE (-3790 4285);
FORCEPROP 1 LAST HDL_POWER VCCIO3
J 1
(-3800 4375);
DISPLAY 0.702128 (-3800 4375);
PAINT GREEN (-3800 4375);
FORCEPROP 2 LAST CDS_LIB logical_power
J 0
(-3800 4325);
DISPLAY INVISIBLE (-3800 4325);
FORCEPROP 1 LAST PATH I3
J 0
(-3750 4350);
DISPLAY 0.872340 (-3750 4350);
PAINT AQUA (-3750 4350);
DISPLAY INVISIBLE (-3750 4350);
FORCEADD QUANTA_TITLE_BLOCK_C..1
(0 0);
FORCEPROP 0 LAST CDS_CON_LAST_MODIFIED Fri Aug 25 17:25:44 2023
J 0
(-1885 15);
DISPLAY INVISIBLE (-1885 15);
FORCEPROP 2 LAST Q_DEPT 
J 1
(-3763 49);
DISPLAY 1.957447 (-3763 49);
PAINT GREEN (-3763 49);
FORCEPROP 1 LAST CUSTOM_TXT_CDS <CON_LAST_MODIFIED>
J 0
(-1885 15);
DISPLAY 0.978723 (-1885 15);
FORCEPROP 2 LAST CUSTOM_TXT_CDS <XR_PAGE_TITLE>
J 0
(-7890 5250);
DISPLAY 0.638298 (-7890 5250);
PAINT PINK (-7890 5250);
DISPLAY INVISIBLE (-7890 5250);
FORCEPROP 1 LAST CUSTOM_TXT_CDS <NAME_2>
J 0
(-3175 50);
FORCEPROP 1 LAST CUSTOM_TXT_CDS <NAME_1>
J 0
(-3175 175);
FORCEPROP 1 LAST CUSTOM_TXT_CDS <Q_NUMBER>
J 0
(-1403 103);
DISPLAY 1.212766 (-1403 103);
FORCEPROP 1 LAST CUSTOM_TXT_CDS <Q_PROJ>
J 0
(-2382 102);
DISPLAY 1.212766 (-2382 102);
FORCEPROP 1 LAST CUSTOM_TXT_CDS <Q_REV>
J 0
(-184 103);
DISPLAY 1.212766 (-184 103);
FORCEPROP 1 LAST CUSTOM_TXT_CDS <CON_PAGE_NUM> OF <CON_TOTAL_PAGES>
J 0
(-446 18);
DISPLAY 0.978723 (-446 18);
FORCEPROP 1 LAST Q_TITLE FPGA 4/8
J 0
(-9366 26);
DISPLAY 2.446809 (-9366 26);
PAINT GREEN (-9366 26);
FORCEPROP 2 LAST CDS_LIB pure_quanta
J 0
(0 0);
DISPLAY INVISIBLE (0 0);
FORCEPROP 1 LAST COMMENT_BODY TRUE
J 0
(12 -13);
DISPLAY 0.978723 (12 -13);
PAINT GREEN (12 -13);
DISPLAY INVISIBLE (12 -13);
FORCEPROP 1 LAST CDS_LMAN_SYM_OUTLINE -9475,6775,100,-125
J 0
(0 0);
DISPLAY 0.468085 (0 0);
PAINT GREEN (0 0);
DISPLAY INVISIBLE (0 0);
FORCEPROP 2 LAST PAGE_BORDER TRUE
J 0
(-7890 5250);
DISPLAY 0.638298 (-7890 5250);
PAINT PINK (-7890 5250);
DISPLAY INVISIBLE (-7890 5250);
FORCEPROP 2 LAST CDS_XR_PAGE_TITLE CR-37 : @SCM_LIB.SCM(SCH_1):PAGE37
J 0
(-7890 5250);
DISPLAY 0.638298 (-7890 5250);
PAINT PINK (-7890 5250);
DISPLAY INVISIBLE (-7890 5250);
WIRE 16 -1 (-3800 4275)(-3800 4225);
WIRE 16 -1 (-3800 4225)(-4175 4225);
QUIT
